(kicad_pcb
	(version 20260206)
	(generator "pcbnew")
	(generator_version "10.0")
	(general
		(thickness 1.6)
		(legacy_teardrops no)
	)
	(paper "A4")
	(title_block
		(title "04192023_DAF0TMB3IC0_F0TG_MB_C_brd_V02_OCP.brd")
		(comment 1 "Grand Teton / footprints 3709-3713 of 8354")
	)
	(layers
		(0 "F.Cu" signal "TOP")
		(4 "In1.Cu" signal "GND")
		(6 "In2.Cu" signal "IN1")
		(8 "In3.Cu" signal "GND1")
		(10 "In4.Cu" signal "IN2")
		(12 "In5.Cu" signal "GND2")
		(14 "In6.Cu" signal "IN3")
		(16 "In7.Cu" signal "GND3")
		(18 "In8.Cu" signal "VCC")
		(20 "In9.Cu" signal "VCC1")
		(22 "In10.Cu" signal "GND4")
		(24 "In11.Cu" signal "IN4")
		(26 "In12.Cu" signal "GND5")
		(28 "In13.Cu" signal "IN5")
		(30 "In14.Cu" signal "GND6")
		(32 "In15.Cu" signal "IN6")
		(34 "In16.Cu" signal "GND7")
		(2 "B.Cu" signal "BOTTOM")
		(9 "F.Adhes" user "F.Adhesive")
		(11 "B.Adhes" user "B.Adhesive")
		(13 "F.Paste" user "Package Geometry/Pastemask Top")
		(15 "B.Paste" user "Package Geometry/Pastemask Bottom")
		(5 "F.SilkS" user "Ref Des/Silkscreen Top")
		(7 "B.SilkS" user "Ref Des/Silkscreen Bottom")
		(1 "F.Mask" user "Board Geometry/Soldermask Top")
		(3 "B.Mask" user "Board Geometry/Soldermask Bottom")
		(17 "Dwgs.User" user "User.Drawings")
		(19 "Cmts.User" user "User.Comments")
		(21 "Eco1.User" user "User.Eco1")
		(23 "Eco2.User" user "User.Eco2")
		(25 "Edge.Cuts" user "Board Geometry/Outline")
		(27 "Margin" user)
		(31 "F.CrtYd" user "Package Geometry/Place Bound Top")
		(29 "B.CrtYd" user "Package Geometry/Place Bound Bottom")
		(35 "F.Fab" user "Ref Des/Assembly Top")
		(33 "B.Fab" user "Ref Des/Assembly Bottom")
	)
	(footprint ""
		(layer "F.Cu")
		(at 91.45143 -58.33237 180)
		(property "Reference" "PU200"
			(at 2.957068 2.756662 0)
			(unlocked yes)
			(layer "F.SilkS")
			(effects
				(font
					(size 0.7874 0.5842)
					(thickness 0.1524)
				)
				(justify left)
			)
		)
		(property "Value" ""
			(at 0 0 180)
			(layer "F.Fab")
			(effects
				(font
					(size 1.27 1.27)
				)
			)
		)
		(duplicate_pad_numbers_are_jumpers no)
		(fp_line
			(start 1.774952 1.039876)
			(end 1.774952 -1.039876)
			(stroke
				(width 0.1524)
				(type default)
			)
			(layer "F.SilkS")
		)
		(fp_line
			(start 1.774952 -1.039876)
			(end -1.774952 -1.039876)
			(stroke
				(width 0.1524)
				(type default)
			)
			(layer "F.SilkS")
		)
		(fp_line
			(start -1.774952 1.039876)
			(end 1.774952 1.039876)
			(stroke
				(width 0.1524)
				(type default)
			)
			(layer "F.SilkS")
		)
		(fp_line
			(start -1.774952 -1.039876)
			(end -1.774952 1.039876)
			(stroke
				(width 0.1524)
				(type default)
			)
			(layer "F.SilkS")
		)
		(fp_poly
			(pts
				(xy -0.999998 -1.801876) (xy -0.999998 -1.039876) (xy -1.769872 -1.039876) (xy -1.769872 -0.249936)
				(xy -2.531872 -0.249936) (xy -2.531872 -1.801876)
			)
			(stroke
				(width 0)
				(type default)
			)
			(fill yes)
			(layer "F.SilkS")
		)
		(fp_line
			(start 1.769872 1.039876)
			(end 1.769872 -1.039876)
			(stroke
				(width 0.1)
				(type default)
			)
			(layer "F.Fab")
		)
		(fp_line
			(start 1.769872 -1.039876)
			(end -1.769872 -1.039876)
			(stroke
				(width 0.1)
				(type default)
			)
			(layer "F.Fab")
		)
		(fp_line
			(start -1.769872 1.039876)
			(end 1.769872 1.039876)
			(stroke
				(width 0.1)
				(type default)
			)
			(layer "F.Fab")
		)
		(fp_line
			(start -1.769872 -1.039876)
			(end -1.769872 1.039876)
			(stroke
				(width 0.1)
				(type default)
			)
			(layer "F.Fab")
		)
		(fp_poly
			(pts
				(xy -1.769872 -1.039876) (xy -0.999998 -1.039876) (xy -0.999998 -1.801876) (xy -2.531872 -1.801876)
				(xy -2.531872 -0.249936) (xy -1.769872 -0.249936)
			)
			(stroke
				(width 0)
				(type default)
			)
			(fill yes)
			(layer "F.Fab")
		)
		(pad "A1" smd circle
			(at -1.500124 -0.750062 180)
			(size 0.2286 0.2286)
			(layers "F.Cu" "F.Mask" "F.Paste")
			(net "P3V3_OCP_SENSE_2")
		)
		(pad "A2" smd circle
			(at -0.999998 -0.750062 180)
			(size 0.2286 0.2286)
			(layers "F.Cu" "F.Mask" "F.Paste")
			(net "P3V3_OCP_VCC_2")
		)
		(pad "A3" smd circle
			(at -0.499872 -0.750062 180)
			(size 0.2286 0.2286)
			(layers "F.Cu" "F.Mask" "F.Paste")
			(net "P3V3_AUX")
		)
		(pad "A4" smd circle
			(at 0 -0.750062 180)
			(size 0.2286 0.2286)
			(layers "F.Cu" "F.Mask" "F.Paste")
			(net "P3V3_OCP_V3_2_R")
		)
		(pad "A5" smd circle
			(at 0.499872 -0.750062 180)
			(size 0.2286 0.2286)
			(layers "F.Cu" "F.Mask" "F.Paste")
			(net "P3V3_AUX")
		)
		(pad "A6" smd circle
			(at 0.999998 -0.750062 180)
			(size 0.2286 0.2286)
			(layers "F.Cu" "F.Mask" "F.Paste")
			(net "P3V3_OCP_GATE_2")
		)
		(pad "A7" smd circle
			(at 1.500124 -0.750062 180)
			(size 0.2286 0.2286)
			(layers "F.Cu" "F.Mask" "F.Paste")
			(net "GND")
		)
		(pad "B1" smd circle
			(at -1.500124 -0.249936 180)
			(size 0.2286 0.2286)
			(layers "F.Cu" "F.Mask" "F.Paste")
			(net "P3V3_OCP_CB_2")
		)
		(pad "B2" smd circle
			(at -0.999998 -0.249936 180)
			(size 0.2286 0.2286)
			(layers "F.Cu" "F.Mask" "F.Paste")
			(net "GND")
		)
		(pad "B3" smd circle
			(at -0.499872 -0.249936 180)
			(size 0.2286 0.2286)
			(layers "F.Cu" "F.Mask" "F.Paste")
			(net "P3V3_AUX")
		)
		(pad "B4" smd circle
			(at 0 -0.249936 180)
			(size 0.2286 0.2286)
			(layers "F.Cu" "F.Mask" "F.Paste")
			(net "P3V3_OCP_V3_2_R")
		)
		(pad "B5" smd circle
			(at 0.499872 -0.249936 180)
			(size 0.2286 0.2286)
			(layers "F.Cu" "F.Mask" "F.Paste")
			(net "P3V3_AUX")
		)
		(pad "B6" smd circle
			(at 0.999998 -0.249936 180)
			(size 0.2286 0.2286)
			(layers "F.Cu" "F.Mask" "F.Paste")
			(net "P3V3_OCP_V3_2_R")
		)
		(pad "B7" smd circle
			(at 1.500124 -0.249936 180)
			(size 0.2286 0.2286)
			(layers "F.Cu" "F.Mask" "F.Paste")
			(net "GND")
		)
		(pad "C1" smd circle
			(at -1.500124 0.249936 180)
			(size 0.2286 0.2286)
			(layers "F.Cu" "F.Mask" "F.Paste")
			(net "GND")
		)
		(pad "C2" smd circle
			(at -0.999998 0.249936 180)
			(size 0.2286 0.2286)
			(layers "F.Cu" "F.Mask" "F.Paste")
			(net "GND")
		)
		(pad "C3" smd circle
			(at -0.499872 0.249936 180)
			(size 0.2286 0.2286)
			(layers "F.Cu" "F.Mask" "F.Paste")
			(net "P3V3_AUX")
		)
		(pad "C4" smd circle
			(at 0 0.249936 180)
			(size 0.2286 0.2286)
			(layers "F.Cu" "F.Mask" "F.Paste")
			(net "P3V3_OCP_V3_2_R")
		)
		(pad "C5" smd circle
			(at 0.499872 0.249936 180)
			(size 0.2286 0.2286)
			(layers "F.Cu" "F.Mask" "F.Paste")
			(net "P3V3_AUX")
		)
		(pad "C6" smd circle
			(at 0.999998 0.249936 180)
			(size 0.2286 0.2286)
			(layers "F.Cu" "F.Mask" "F.Paste")
			(net "P3V3_OCP_V3_2_R")
		)
		(pad "C7" smd circle
			(at 1.500124 0.249936 180)
			(size 0.2286 0.2286)
			(layers "F.Cu" "F.Mask" "F.Paste")
			(net "P3V3_OCP_FAULT_2")
		)
		(pad "D1" smd circle
			(at -1.500124 0.750062 180)
			(size 0.2286 0.2286)
			(layers "F.Cu" "F.Mask" "F.Paste")
			(net "P3V3_OCP_REG_2")
		)
		(pad "D2" smd circle
			(at -0.999998 0.750062 180)
			(size 0.2286 0.2286)
			(layers "F.Cu" "F.Mask" "F.Paste")
			(net "P3V3_OCP_UV_2")
		)
		(pad "D3" smd circle
			(at -0.499872 0.750062 180)
			(size 0.2286 0.2286)
			(layers "F.Cu" "F.Mask" "F.Paste")
			(net "P3V3_OCP_OV_2")
		)
		(pad "D4" smd circle
			(at 0 0.750062 180)
			(size 0.2286 0.2286)
			(layers "F.Cu" "F.Mask" "F.Paste")
			(net "P3V3_OCP_V3_2_R")
		)
		(pad "D5" smd circle
			(at 0.499872 0.750062 180)
			(size 0.2286 0.2286)
			(layers "F.Cu" "F.Mask" "F.Paste")
			(net "P3V3_AUX")
		)
		(pad "D6" smd circle
			(at 0.999998 0.750062 180)
			(size 0.2286 0.2286)
			(layers "F.Cu" "F.Mask" "F.Paste")
			(net "P3V3_OCP_V3_2_R")
		)
		(pad "D7" smd circle
			(at 1.500124 0.750062 180)
			(size 0.2286 0.2286)
			(layers "F.Cu" "F.Mask" "F.Paste")
			(net "P3V3_OCP_PWRGD_2")
		)
	)
	(footprint ""
		(layer "F.Cu")
		(at 236.7661 -401.887182)
		(property "Reference" "PC2225"
			(at 0 0 0)
			(layer "F.SilkS")
			(hide yes)
			(effects
				(font
					(size 1.27 1.27)
				)
			)
		)
		(property "Value" ""
			(at 0 0 0)
			(layer "F.Fab")
			(effects
				(font
					(size 1.27 1.27)
				)
			)
		)
		(duplicate_pad_numbers_are_jumpers no)
		(fp_line
			(start -0.7874 -0.4064)
			(end 0.7874 -0.4064)
			(stroke
				(width 0.1524)
				(type default)
			)
			(layer "F.SilkS")
		)
		(fp_line
			(start -0.7874 0.4064)
			(end -0.7874 -0.4064)
			(stroke
				(width 0.1524)
				(type default)
			)
			(layer "F.SilkS")
		)
		(fp_line
			(start 0.7874 -0.4064)
			(end 0.7874 0.4064)
			(stroke
				(width 0.1524)
				(type default)
			)
			(layer "F.SilkS")
		)
		(fp_line
			(start 0.7874 0.4064)
			(end -0.7874 0.4064)
			(stroke
				(width 0.1524)
				(type default)
			)
			(layer "F.SilkS")
		)
		(fp_line
			(start -0.67945 -0.305054)
			(end -0.12065 -0.305054)
			(stroke
				(width 0.1)
				(type default)
			)
			(layer "F.Fab")
		)
		(fp_line
			(start -0.67945 0.3048)
			(end -0.67945 -0.305054)
			(stroke
				(width 0.1)
				(type default)
			)
			(layer "F.Fab")
		)
		(fp_line
			(start -0.12065 -0.305054)
			(end -0.12065 -0.2794)
			(stroke
				(width 0.1)
				(type default)
			)
			(layer "F.Fab")
		)
		(fp_line
			(start -0.12065 -0.2794)
			(end 0.12065 -0.2794)
			(stroke
				(width 0.1)
				(type default)
			)
			(layer "F.Fab")
		)
		(fp_line
			(start -0.12065 0.2794)
			(end -0.12065 0.3048)
			(stroke
				(width 0.1)
				(type default)
			)
			(layer "F.Fab")
		)
		(fp_line
			(start -0.12065 0.3048)
			(end -0.67945 0.3048)
			(stroke
				(width 0.1)
				(type default)
			)
			(layer "F.Fab")
		)
		(fp_line
			(start 0.120396 0.2794)
			(end -0.12065 0.2794)
			(stroke
				(width 0.1)
				(type default)
			)
			(layer "F.Fab")
		)
		(fp_line
			(start 0.120396 0.3048)
			(end 0.120396 0.2794)
			(stroke
				(width 0.1)
				(type default)
			)
			(layer "F.Fab")
		)
		(fp_line
			(start 0.12065 -0.3048)
			(end 0.67945 -0.3048)
			(stroke
				(width 0.1)
				(type default)
			)
			(layer "F.Fab")
		)
		(fp_line
			(start 0.12065 -0.2794)
			(end 0.12065 -0.3048)
			(stroke
				(width 0.1)
				(type default)
			)
			(layer "F.Fab")
		)
		(fp_line
			(start 0.67945 -0.3048)
			(end 0.67945 0.3048)
			(stroke
				(width 0.1)
				(type default)
			)
			(layer "F.Fab")
		)
		(fp_line
			(start 0.67945 0.3048)
			(end 0.120396 0.3048)
			(stroke
				(width 0.1)
				(type default)
			)
			(layer "F.Fab")
		)
		(pad "1" smd circle
			(at -0.40005 0)
			(size 0 0)
			(layers "F.Cu" "F.Mask" "F.Paste")
			(net "HSC_ON")
		)
		(pad "2" smd circle
			(at 0.40005 0)
			(size 0 0)
			(layers "F.Cu" "F.Mask" "F.Paste")
			(net "AGND_HSC")
		)
	)
	(footprint ""
		(layer "F.Cu")
		(at 136.101328 -158.265368 -90)
		(property "Reference" "PR511"
			(at 0 0 270)
			(layer "F.SilkS")
			(hide yes)
			(effects
				(font
					(size 1.27 1.27)
				)
			)
		)
		(property "Value" ""
			(at 0 0 270)
			(layer "F.Fab")
			(effects
				(font
					(size 1.27 1.27)
				)
			)
		)
		(duplicate_pad_numbers_are_jumpers no)
		(fp_line
			(start -0.7874 0.4064)
			(end -0.7874 -0.4064)
			(stroke
				(width 0.1524)
				(type default)
			)
			(layer "F.SilkS")
		)
		(fp_line
			(start 0.7874 0.4064)
			(end -0.7874 0.4064)
			(stroke
				(width 0.1524)
				(type default)
			)
			(layer "F.SilkS")
		)
		(fp_line
			(start -0.7874 -0.4064)
			(end 0.7874 -0.4064)
			(stroke
				(width 0.1524)
				(type default)
			)
			(layer "F.SilkS")
		)
		(fp_line
			(start 0.7874 -0.4064)
			(end 0.7874 0.4064)
			(stroke
				(width 0.1524)
				(type default)
			)
			(layer "F.SilkS")
		)
		(fp_line
			(start -0.67945 0.3048)
			(end -0.67945 -0.305054)
			(stroke
				(width 0.1)
				(type default)
			)
			(layer "F.Fab")
		)
		(fp_line
			(start -0.12065 0.3048)
			(end -0.67945 0.3048)
			(stroke
				(width 0.1)
				(type default)
			)
			(layer "F.Fab")
		)
		(fp_line
			(start 0.120396 0.3048)
			(end 0.120396 0.2794)
			(stroke
				(width 0.1)
				(type default)
			)
			(layer "F.Fab")
		)
		(fp_line
			(start 0.67945 0.3048)
			(end 0.120396 0.3048)
			(stroke
				(width 0.1)
				(type default)
			)
			(layer "F.Fab")
		)
		(fp_line
			(start -0.12065 0.2794)
			(end -0.12065 0.3048)
			(stroke
				(width 0.1)
				(type default)
			)
			(layer "F.Fab")
		)
		(fp_line
			(start 0.120396 0.2794)
			(end -0.12065 0.2794)
			(stroke
				(width 0.1)
				(type default)
			)
			(layer "F.Fab")
		)
		(fp_line
			(start -0.12065 -0.2794)
			(end 0.12065 -0.2794)
			(stroke
				(width 0.1)
				(type default)
			)
			(layer "F.Fab")
		)
		(fp_line
			(start 0.12065 -0.2794)
			(end 0.12065 -0.3048)
			(stroke
				(width 0.1)
				(type default)
			)
			(layer "F.Fab")
		)
		(fp_line
			(start 0.12065 -0.3048)
			(end 0.67945 -0.3048)
			(stroke
				(width 0.1)
				(type default)
			)
			(layer "F.Fab")
		)
		(fp_line
			(start 0.67945 -0.3048)
			(end 0.67945 0.3048)
			(stroke
				(width 0.1)
				(type default)
			)
			(layer "F.Fab")
		)
		(fp_line
			(start -0.67945 -0.305054)
			(end -0.12065 -0.305054)
			(stroke
				(width 0.1)
				(type default)
			)
			(layer "F.Fab")
		)
		(fp_line
			(start -0.12065 -0.305054)
			(end -0.12065 -0.2794)
			(stroke
				(width 0.1)
				(type default)
			)
			(layer "F.Fab")
		)
		(pad "1" smd circle
			(at -0.40005 0 270)
			(size 0 0)
			(layers "F.Cu" "F.Mask" "F.Paste")
			(net "SW_PVDDCR_SOC_P1_SW3_RC")
		)
		(pad "2" smd circle
			(at 0.40005 0 270)
			(size 0 0)
			(layers "F.Cu" "F.Mask" "F.Paste")
			(net "GND")
		)
	)
	(footprint ""
		(layer "F.Cu")
		(at 434.43144 -434.467508 90)
		(property "Reference" "R2836"
			(at 0 0 90)
			(layer "F.SilkS")
			(hide yes)
			(effects
				(font
					(size 1.27 1.27)
				)
			)
		)
		(property "Value" ""
			(at 0 0 90)
			(layer "F.Fab")
			(effects
				(font
					(size 1.27 1.27)
				)
			)
		)
		(duplicate_pad_numbers_are_jumpers no)
		(fp_line
			(start 0.7874 -0.4064)
			(end 0.7874 0.4064)
			(stroke
				(width 0.1524)
				(type default)
			)
			(layer "F.SilkS")
		)
		(fp_line
			(start -0.7874 -0.4064)
			(end 0.7874 -0.4064)
			(stroke
				(width 0.1524)
				(type default)
			)
			(layer "F.SilkS")
		)
		(fp_line
			(start 0.7874 0.4064)
			(end -0.7874 0.4064)
			(stroke
				(width 0.1524)
				(type default)
			)
			(layer "F.SilkS")
		)
		(fp_line
			(start -0.7874 0.4064)
			(end -0.7874 -0.4064)
			(stroke
				(width 0.1524)
				(type default)
			)
			(layer "F.SilkS")
		)
		(fp_line
			(start -0.12065 -0.305054)
			(end -0.12065 -0.2794)
			(stroke
				(width 0.1)
				(type default)
			)
			(layer "F.Fab")
		)
		(fp_line
			(start -0.67945 -0.305054)
			(end -0.12065 -0.305054)
			(stroke
				(width 0.1)
				(type default)
			)
			(layer "F.Fab")
		)
		(fp_line
			(start 0.67945 -0.3048)
			(end 0.67945 0.3048)
			(stroke
				(width 0.1)
				(type default)
			)
			(layer "F.Fab")
		)
		(fp_line
			(start 0.12065 -0.3048)
			(end 0.67945 -0.3048)
			(stroke
				(width 0.1)
				(type default)
			)
			(layer "F.Fab")
		)
		(fp_line
			(start 0.12065 -0.2794)
			(end 0.12065 -0.3048)
			(stroke
				(width 0.1)
				(type default)
			)
			(layer "F.Fab")
		)
		(fp_line
			(start -0.12065 -0.2794)
			(end 0.12065 -0.2794)
			(stroke
				(width 0.1)
				(type default)
			)
			(layer "F.Fab")
		)
		(fp_line
			(start 0.120396 0.2794)
			(end -0.12065 0.2794)
			(stroke
				(width 0.1)
				(type default)
			)
			(layer "F.Fab")
		)
		(fp_line
			(start -0.12065 0.2794)
			(end -0.12065 0.3048)
			(stroke
				(width 0.1)
				(type default)
			)
			(layer "F.Fab")
		)
		(fp_line
			(start 0.67945 0.3048)
			(end 0.120396 0.3048)
			(stroke
				(width 0.1)
				(type default)
			)
			(layer "F.Fab")
		)
		(fp_line
			(start 0.120396 0.3048)
			(end 0.120396 0.2794)
			(stroke
				(width 0.1)
				(type default)
			)
			(layer "F.Fab")
		)
		(fp_line
			(start -0.12065 0.3048)
			(end -0.67945 0.3048)
			(stroke
				(width 0.1)
				(type default)
			)
			(layer "F.Fab")
		)
		(fp_line
			(start -0.67945 0.3048)
			(end -0.67945 -0.305054)
			(stroke
				(width 0.1)
				(type default)
			)
			(layer "F.Fab")
		)
		(pad "1" smd circle
			(at -0.40005 0 90)
			(size 0 0)
			(layers "F.Cu" "F.Mask" "F.Paste")
			(net "P3V3_AUX")
		)
		(pad "2" smd circle
			(at 0.40005 0 90)
			(size 0 0)
			(layers "F.Cu" "F.Mask" "F.Paste")
			(net "FM_SWB_BIC_READY")
		)
	)
	(footprint ""
		(layer "F.Cu")
		(at 408.04084 -378.95403 -90)
		(property "Reference" "C856"
			(at 0 0 270)
			(layer "F.SilkS")
			(hide yes)
			(effects
				(font
					(size 1.27 1.27)
				)
			)
		)
		(property "Value" ""
			(at 0 0 270)
			(layer "F.Fab")
			(effects
				(font
					(size 1.27 1.27)
				)
			)
		)
		(duplicate_pad_numbers_are_jumpers no)
		(fp_line
			(start -0.299974 0.150114)
			(end -0.299974 -0.150114)
			(stroke
				(width 0.1)
				(type default)
			)
			(layer "F.Fab")
		)
		(fp_line
			(start 0.299974 0.150114)
			(end -0.299974 0.150114)
			(stroke
				(width 0.1)
				(type default)
			)
			(layer "F.Fab")
		)
		(fp_line
			(start -0.299974 -0.150114)
			(end 0.299974 -0.150114)
			(stroke
				(width 0.1)
				(type default)
			)
			(layer "F.Fab")
		)
		(fp_line
			(start 0.299974 -0.150114)
			(end 0.299974 0.150114)
			(stroke
				(width 0.1)
				(type default)
			)
			(layer "F.Fab")
		)
		(pad "1" smd rect
			(at -0.2667 0 270)
			(size 0.3048 0.381)
			(layers "F.Cu" "F.Mask" "F.Paste")
			(net "P5E_CPU0_P2_TX_C_DN<6>")
		)
		(pad "2" smd rect
			(at 0.2667 0 270)
			(size 0.3048 0.381)
			(layers "F.Cu" "F.Mask" "F.Paste")
			(net "P5E_CPU0_P2_TX_DN<6>")
		)
	)
)
